FILE_TYPE = MACRO_DRAWING;
SET COLOR_WIRE YELLOW;
SET COLOR_PROP ORANGE;
SET COLOR_DOT WHITE;
SET COLOR_ARC YELLOW;
SET COLOR_BODY GREEN;
SET COLOR_NOTE PURPLE;
SET PROP_DISPLAY VALUE;
SET PAGE_NUMBER P247;
FORCEADD QUANTA_TITLE_BLOCK_C..1
(-1075 2675);
FORCEPROP 1 LAST CUSTOM_TXT_CDS <NAME_2>
J 0
(-4250 2725);
FORCEPROP 1 LAST CUSTOM_TXT_CDS <NAME_1>
J 0
(-4250 2850);
FORCEPROP 1 LAST CUSTOM_TXT_CDS <Q_NUMBER>
J 0
(-2478 2778);
DISPLAY 1.212766 (-2478 2778);
FORCEPROP 1 LAST CUSTOM_TXT_CDS <Q_PROJ>
J 0
(-3457 2777);
DISPLAY 1.212766 (-3457 2777);
FORCEPROP 1 LAST CUSTOM_TXT_CDS <Q_REV>
J 0
(-1259 2778);
DISPLAY 1.212766 (-1259 2778);
FORCEPROP 1 LAST CUSTOM_TXT_CDS <CON_LAST_MODIFIED>
J 0
(-2960 2690);
DISPLAY 0.978723 (-2960 2690);
FORCEPROP 1 LAST CUSTOM_TXT_CDS <CON_PAGE_NUM> OF <CON_TOTAL_PAGES>
J 0
(-1521 2693);
DISPLAY 0.978723 (-1521 2693);
FORCEPROP 1 LAST Q_TITLE BLANK
J 0
(-10300 2775);
DISPLAY 2.446809 (-10300 2775);
PAINT GREEN (-10300 2775);
FORCEPROP 1 LAST Q_DEPT 
J 1
(-4838 2724);
DISPLAY 1.957447 (-4838 2724);
PAINT GREEN (-4838 2724);
FORCEPROP 2 LAST CDS_XR_PAGE_TITLE CR-261 : @S9S_MB_2U_LIB.S9S_MB_2U(SCH_1):PAGE261
J 0
(-8965 7925);
DISPLAY 0.638298 (-8965 7925);
PAINT PINK (-8965 7925);
DISPLAY INVISIBLE (-8965 7925);
FORCEPROP 2 LAST PAGE_BORDER TRUE
J 0
(-8965 7925);
DISPLAY 0.638298 (-8965 7925);
PAINT PINK (-8965 7925);
DISPLAY INVISIBLE (-8965 7925);
FORCEPROP 1 LAST COMMENT_BODY TRUE
J 0
(-1063 2662);
DISPLAY 0.978723 (-1063 2662);
PAINT GREEN (-1063 2662);
DISPLAY INVISIBLE (-1063 2662);
FORCEPROP 1 LAST CDS_LMAN_SYM_OUTLINE -9475,6775,100,-125
J 0
(-1075 2675);
DISPLAY 0.468085 (-1075 2675);
PAINT GREEN (-1075 2675);
DISPLAY INVISIBLE (-1075 2675);
FORCEPROP 2 LAST CDS_LIB pure_quanta
J 0
(-1075 2675);
DISPLAY INVISIBLE (-1075 2675);
FORCEPROP 2 LAST CUSTOM_TXT_CDS <XR_PAGE_TITLE>
J 0
(-8965 7925);
DISPLAY 0.638298 (-8965 7925);
PAINT PINK (-8965 7925);
DISPLAY INVISIBLE (-8965 7925);
FORCEPROP 0 LAST CDS_CON_LAST_MODIFIED Thu Aug 24 16:16:18 2023
J 0
(-2960 2690);
DISPLAY INVISIBLE (-2960 2690);
FORCENOTE
THIS PAGE WAS INTENTIONALLY LEFT BLANK
(-10075 6000) 0;
DISPLAY LEFT (-10075 6000);
DISPLAY 4.914894 (-10075 6000);
QUIT
